(kicad_pcb
	(version 20260206)
	(generator "pcbnew")
	(generator_version "10.0")
	(general
		(thickness 1.6)
		(legacy_teardrops no)
	)
	(paper "A4")
	(title_block
		(title "03242023_DA0F0TMBIJ0_F0T_Motherboard_J_brd_V01_OCP.brd")
		(comment 1 "Grand Teton / footprints 4817-4823 of 6105")
	)
	(layers
		(0 "F.Cu" signal "TOP")
		(4 "In1.Cu" signal "GND")
		(6 "In2.Cu" signal "IN1")
		(8 "In3.Cu" signal "GND1")
		(10 "In4.Cu" signal "IN2")
		(12 "In5.Cu" signal "GND2")
		(14 "In6.Cu" signal "IN3")
		(16 "In7.Cu" signal "GND3")
		(18 "In8.Cu" signal "VCC")
		(20 "In9.Cu" signal "VCC1")
		(22 "In10.Cu" signal "GND4")
		(24 "In11.Cu" signal "IN4")
		(26 "In12.Cu" signal "GND5")
		(28 "In13.Cu" signal "IN5")
		(30 "In14.Cu" signal "GND6")
		(32 "In15.Cu" signal "IN6")
		(34 "In16.Cu" signal "GND7")
		(2 "B.Cu" signal "BOTTOM")
		(9 "F.Adhes" user "F.Adhesive")
		(11 "B.Adhes" user "B.Adhesive")
		(13 "F.Paste" user "Package Geometry/Pastemask Top")
		(15 "B.Paste" user "Package Geometry/Pastemask Bottom")
		(5 "F.SilkS" user "Ref Des/Silkscreen Top")
		(7 "B.SilkS" user "Ref Des/Silkscreen Bottom")
		(1 "F.Mask" user "Board Geometry/Soldermask Top")
		(3 "B.Mask" user "Board Geometry/Soldermask Bottom")
		(17 "Dwgs.User" user "User.Drawings")
		(19 "Cmts.User" user "User.Comments")
		(21 "Eco1.User" user "User.Eco1")
		(23 "Eco2.User" user "User.Eco2")
		(25 "Edge.Cuts" user "Board Geometry/Outline")
		(27 "Margin" user)
		(31 "F.CrtYd" user "Package Geometry/Place Bound Top")
		(29 "B.CrtYd" user "Package Geometry/Place Bound Bottom")
		(35 "F.Fab" user "Ref Des/Assembly Top")
		(33 "B.Fab" user "Ref Des/Assembly Bottom")
	)
	(footprint ""
		(layer "B.Cu")
		(at 68.337684 -185.791856 -90)
		(property "Reference" "R1008"
			(at 0 0 90)
			(layer "B.SilkS")
			(hide yes)
			(effects
				(font
					(size 1.27 1.27)
				)
				(justify mirror)
			)
		)
		(property "Value" ""
			(at 0 0 90)
			(layer "B.Fab")
			(effects
				(font
					(size 1.27 1.27)
				)
				(justify mirror)
			)
		)
		(duplicate_pad_numbers_are_jumpers no)
		(fp_line
			(start -0.7874 0.4064)
			(end 0.7874 0.4064)
			(stroke
				(width 0.1524)
				(type default)
			)
			(layer "B.SilkS")
		)
		(fp_line
			(start 0.7874 0.4064)
			(end 0.7874 -0.4064)
			(stroke
				(width 0.1524)
				(type default)
			)
			(layer "B.SilkS")
		)
		(fp_line
			(start -0.7874 -0.4064)
			(end -0.7874 0.4064)
			(stroke
				(width 0.1524)
				(type default)
			)
			(layer "B.SilkS")
		)
		(fp_line
			(start 0.7874 -0.4064)
			(end -0.7874 -0.4064)
			(stroke
				(width 0.1524)
				(type default)
			)
			(layer "B.SilkS")
		)
		(fp_line
			(start -0.67945 0.3048)
			(end -0.120396 0.3048)
			(stroke
				(width 0.1)
				(type default)
			)
			(layer "B.Fab")
		)
		(fp_line
			(start -0.120396 0.3048)
			(end -0.120396 0.2794)
			(stroke
				(width 0.1)
				(type default)
			)
			(layer "B.Fab")
		)
		(fp_line
			(start 0.12065 0.3048)
			(end 0.67945 0.3048)
			(stroke
				(width 0.1)
				(type default)
			)
			(layer "B.Fab")
		)
		(fp_line
			(start 0.67945 0.3048)
			(end 0.67945 -0.305054)
			(stroke
				(width 0.1)
				(type default)
			)
			(layer "B.Fab")
		)
		(fp_line
			(start -0.120396 0.2794)
			(end 0.12065 0.2794)
			(stroke
				(width 0.1)
				(type default)
			)
			(layer "B.Fab")
		)
		(fp_line
			(start 0.12065 0.2794)
			(end 0.12065 0.3048)
			(stroke
				(width 0.1)
				(type default)
			)
			(layer "B.Fab")
		)
		(fp_line
			(start -0.12065 -0.2794)
			(end -0.12065 -0.3048)
			(stroke
				(width 0.1)
				(type default)
			)
			(layer "B.Fab")
		)
		(fp_line
			(start 0.12065 -0.2794)
			(end -0.12065 -0.2794)
			(stroke
				(width 0.1)
				(type default)
			)
			(layer "B.Fab")
		)
		(fp_line
			(start -0.67945 -0.3048)
			(end -0.67945 0.3048)
			(stroke
				(width 0.1)
				(type default)
			)
			(layer "B.Fab")
		)
		(fp_line
			(start -0.12065 -0.3048)
			(end -0.67945 -0.3048)
			(stroke
				(width 0.1)
				(type default)
			)
			(layer "B.Fab")
		)
		(fp_line
			(start 0.12065 -0.305054)
			(end 0.12065 -0.2794)
			(stroke
				(width 0.1)
				(type default)
			)
			(layer "B.Fab")
		)
		(fp_line
			(start 0.67945 -0.305054)
			(end 0.12065 -0.305054)
			(stroke
				(width 0.1)
				(type default)
			)
			(layer "B.Fab")
		)
		(pad "1" smd circle
			(at 0.40005 0 90)
			(size 0 0)
			(layers "B.Cu" "B.Mask" "B.Paste")
			(net "PVNN_TERM_CPU1")
		)
		(pad "2" smd circle
			(at -0.40005 0 90)
			(size 0 0)
			(layers "B.Cu" "B.Mask" "B.Paste")
			(net "PU_TAP_ODT_CPU1_EN")
		)
	)
	(footprint ""
		(layer "B.Cu")
		(at 411.172152 -193.08953 -90)
		(property "Reference" "R97"
			(at 0 0 90)
			(layer "B.SilkS")
			(hide yes)
			(effects
				(font
					(size 1.27 1.27)
				)
				(justify mirror)
			)
		)
		(property "Value" ""
			(at 0 0 90)
			(layer "B.Fab")
			(effects
				(font
					(size 1.27 1.27)
				)
				(justify mirror)
			)
		)
		(duplicate_pad_numbers_are_jumpers no)
		(fp_line
			(start -0.7874 0.4064)
			(end 0.7874 0.4064)
			(stroke
				(width 0.1524)
				(type default)
			)
			(layer "B.SilkS")
		)
		(fp_line
			(start 0.7874 0.4064)
			(end 0.7874 -0.4064)
			(stroke
				(width 0.1524)
				(type default)
			)
			(layer "B.SilkS")
		)
		(fp_line
			(start -0.7874 -0.4064)
			(end -0.7874 0.4064)
			(stroke
				(width 0.1524)
				(type default)
			)
			(layer "B.SilkS")
		)
		(fp_line
			(start 0.7874 -0.4064)
			(end -0.7874 -0.4064)
			(stroke
				(width 0.1524)
				(type default)
			)
			(layer "B.SilkS")
		)
		(fp_line
			(start -0.67945 0.3048)
			(end -0.120396 0.3048)
			(stroke
				(width 0.1)
				(type default)
			)
			(layer "B.Fab")
		)
		(fp_line
			(start -0.120396 0.3048)
			(end -0.120396 0.2794)
			(stroke
				(width 0.1)
				(type default)
			)
			(layer "B.Fab")
		)
		(fp_line
			(start 0.12065 0.3048)
			(end 0.67945 0.3048)
			(stroke
				(width 0.1)
				(type default)
			)
			(layer "B.Fab")
		)
		(fp_line
			(start 0.67945 0.3048)
			(end 0.67945 -0.305054)
			(stroke
				(width 0.1)
				(type default)
			)
			(layer "B.Fab")
		)
		(fp_line
			(start -0.120396 0.2794)
			(end 0.12065 0.2794)
			(stroke
				(width 0.1)
				(type default)
			)
			(layer "B.Fab")
		)
		(fp_line
			(start 0.12065 0.2794)
			(end 0.12065 0.3048)
			(stroke
				(width 0.1)
				(type default)
			)
			(layer "B.Fab")
		)
		(fp_line
			(start -0.12065 -0.2794)
			(end -0.12065 -0.3048)
			(stroke
				(width 0.1)
				(type default)
			)
			(layer "B.Fab")
		)
		(fp_line
			(start 0.12065 -0.2794)
			(end -0.12065 -0.2794)
			(stroke
				(width 0.1)
				(type default)
			)
			(layer "B.Fab")
		)
		(fp_line
			(start -0.67945 -0.3048)
			(end -0.67945 0.3048)
			(stroke
				(width 0.1)
				(type default)
			)
			(layer "B.Fab")
		)
		(fp_line
			(start -0.12065 -0.3048)
			(end -0.67945 -0.3048)
			(stroke
				(width 0.1)
				(type default)
			)
			(layer "B.Fab")
		)
		(fp_line
			(start 0.12065 -0.305054)
			(end 0.12065 -0.2794)
			(stroke
				(width 0.1)
				(type default)
			)
			(layer "B.Fab")
		)
		(fp_line
			(start 0.67945 -0.305054)
			(end 0.12065 -0.305054)
			(stroke
				(width 0.1)
				(type default)
			)
			(layer "B.Fab")
		)
		(pad "1" smd circle
			(at 0.40005 0 90)
			(size 0 0)
			(layers "B.Cu" "B.Mask" "B.Paste")
			(net "PVNN_TERM_CPU0")
		)
		(pad "2" smd circle
			(at -0.40005 0 90)
			(size 0 0)
			(layers "B.Cu" "B.Mask" "B.Paste")
			(net "PU_CPU0_UPI3_AC_COUPLING")
		)
	)
	(footprint ""
		(layer "B.Cu")
		(at 107.457494 -244.82044 -90)
		(property "Reference" "C318"
			(at 0 0 90)
			(layer "B.SilkS")
			(hide yes)
			(effects
				(font
					(size 1.27 1.27)
				)
				(justify mirror)
			)
		)
		(property "Value" ""
			(at 0 0 90)
			(layer "B.Fab")
			(effects
				(font
					(size 1.27 1.27)
				)
				(justify mirror)
			)
		)
		(duplicate_pad_numbers_are_jumpers no)
		(fp_line
			(start -1.524 0.762)
			(end 1.524 0.762)
			(stroke
				(width 0.1524)
				(type default)
			)
			(layer "B.SilkS")
		)
		(fp_line
			(start 1.524 0.762)
			(end 1.524 -0.762)
			(stroke
				(width 0.1524)
				(type default)
			)
			(layer "B.SilkS")
		)
		(fp_line
			(start -1.524 -0.762)
			(end -1.524 0.762)
			(stroke
				(width 0.1524)
				(type default)
			)
			(layer "B.SilkS")
		)
		(fp_line
			(start 1.524 -0.762)
			(end -1.524 -0.762)
			(stroke
				(width 0.1524)
				(type default)
			)
			(layer "B.SilkS")
		)
		(fp_line
			(start -1.1049 0.724916)
			(end -1.1049 -0.724916)
			(stroke
				(width 0.1)
				(type default)
			)
			(layer "B.Fab")
		)
		(fp_line
			(start 1.1049 0.724916)
			(end -1.1049 0.724916)
			(stroke
				(width 0.1)
				(type default)
			)
			(layer "B.Fab")
		)
		(fp_line
			(start -1.1049 -0.724916)
			(end 1.1049 -0.724916)
			(stroke
				(width 0.1)
				(type default)
			)
			(layer "B.Fab")
		)
		(fp_line
			(start 1.1049 -0.724916)
			(end 1.1049 0.724916)
			(stroke
				(width 0.1)
				(type default)
			)
			(layer "B.Fab")
		)
		(pad "1" smd rect
			(at 0.889 0 270)
			(size 1.016 1.27)
			(layers "B.Cu" "B.Mask" "B.Paste")
			(net "PVCCIN_CPU1")
		)
		(pad "2" smd rect
			(at -0.889 0 270)
			(size 1.016 1.27)
			(layers "B.Cu" "B.Mask" "B.Paste")
			(net "GND")
		)
	)
	(footprint ""
		(layer "B.Cu")
		(at 24.0538 -391.483088 90)
		(property "Reference" "C1864"
			(at 0 0 90)
			(layer "B.SilkS")
			(hide yes)
			(effects
				(font
					(size 1.27 1.27)
				)
				(justify mirror)
			)
		)
		(property "Value" ""
			(at 0 0 90)
			(layer "B.Fab")
			(effects
				(font
					(size 1.27 1.27)
				)
				(justify mirror)
			)
		)
		(duplicate_pad_numbers_are_jumpers no)
		(fp_line
			(start 0.7874 -0.4064)
			(end -0.7874 -0.4064)
			(stroke
				(width 0.1524)
				(type default)
			)
			(layer "B.SilkS")
		)
		(fp_line
			(start -0.7874 -0.4064)
			(end -0.7874 0.4064)
			(stroke
				(width 0.1524)
				(type default)
			)
			(layer "B.SilkS")
		)
		(fp_line
			(start 0.7874 0.4064)
			(end 0.7874 -0.4064)
			(stroke
				(width 0.1524)
				(type default)
			)
			(layer "B.SilkS")
		)
		(fp_line
			(start -0.7874 0.4064)
			(end 0.7874 0.4064)
			(stroke
				(width 0.1524)
				(type default)
			)
			(layer "B.SilkS")
		)
		(fp_line
			(start 0.67945 -0.305054)
			(end 0.12065 -0.305054)
			(stroke
				(width 0.1)
				(type default)
			)
			(layer "B.Fab")
		)
		(fp_line
			(start 0.12065 -0.305054)
			(end 0.12065 -0.2794)
			(stroke
				(width 0.1)
				(type default)
			)
			(layer "B.Fab")
		)
		(fp_line
			(start -0.12065 -0.3048)
			(end -0.67945 -0.3048)
			(stroke
				(width 0.1)
				(type default)
			)
			(layer "B.Fab")
		)
		(fp_line
			(start -0.67945 -0.3048)
			(end -0.67945 0.3048)
			(stroke
				(width 0.1)
				(type default)
			)
			(layer "B.Fab")
		)
		(fp_line
			(start 0.12065 -0.2794)
			(end -0.12065 -0.2794)
			(stroke
				(width 0.1)
				(type default)
			)
			(layer "B.Fab")
		)
		(fp_line
			(start -0.12065 -0.2794)
			(end -0.12065 -0.3048)
			(stroke
				(width 0.1)
				(type default)
			)
			(layer "B.Fab")
		)
		(fp_line
			(start 0.12065 0.2794)
			(end 0.12065 0.3048)
			(stroke
				(width 0.1)
				(type default)
			)
			(layer "B.Fab")
		)
		(fp_line
			(start -0.120396 0.2794)
			(end 0.12065 0.2794)
			(stroke
				(width 0.1)
				(type default)
			)
			(layer "B.Fab")
		)
		(fp_line
			(start 0.67945 0.3048)
			(end 0.67945 -0.305054)
			(stroke
				(width 0.1)
				(type default)
			)
			(layer "B.Fab")
		)
		(fp_line
			(start 0.12065 0.3048)
			(end 0.67945 0.3048)
			(stroke
				(width 0.1)
				(type default)
			)
			(layer "B.Fab")
		)
		(fp_line
			(start -0.120396 0.3048)
			(end -0.120396 0.2794)
			(stroke
				(width 0.1)
				(type default)
			)
			(layer "B.Fab")
		)
		(fp_line
			(start -0.67945 0.3048)
			(end -0.120396 0.3048)
			(stroke
				(width 0.1)
				(type default)
			)
			(layer "B.Fab")
		)
		(pad "1" smd circle
			(at 0.40005 0 270)
			(size 0 0)
			(layers "B.Cu" "B.Mask" "B.Paste")
			(net "P3V3_AUX")
		)
		(pad "2" smd circle
			(at -0.40005 0 270)
			(size 0 0)
			(layers "B.Cu" "B.Mask" "B.Paste")
			(net "GND")
		)
	)
	(footprint ""
		(layer "B.Cu")
		(at 364.342934 -241.142266 -90)
		(property "Reference" "C387"
			(at 0 0 90)
			(layer "B.SilkS")
			(hide yes)
			(effects
				(font
					(size 1.27 1.27)
				)
				(justify mirror)
			)
		)
		(property "Value" ""
			(at 0 0 90)
			(layer "B.Fab")
			(effects
				(font
					(size 1.27 1.27)
				)
				(justify mirror)
			)
		)
		(duplicate_pad_numbers_are_jumpers no)
		(fp_line
			(start -1.524 0.762)
			(end 1.524 0.762)
			(stroke
				(width 0.1524)
				(type default)
			)
			(layer "B.SilkS")
		)
		(fp_line
			(start 1.524 0.762)
			(end 1.524 -0.762)
			(stroke
				(width 0.1524)
				(type default)
			)
			(layer "B.SilkS")
		)
		(fp_line
			(start -1.524 -0.762)
			(end -1.524 0.762)
			(stroke
				(width 0.1524)
				(type default)
			)
			(layer "B.SilkS")
		)
		(fp_line
			(start 1.524 -0.762)
			(end -1.524 -0.762)
			(stroke
				(width 0.1524)
				(type default)
			)
			(layer "B.SilkS")
		)
		(fp_line
			(start -1.1049 0.724916)
			(end -1.1049 -0.724916)
			(stroke
				(width 0.1)
				(type default)
			)
			(layer "B.Fab")
		)
		(fp_line
			(start 1.1049 0.724916)
			(end -1.1049 0.724916)
			(stroke
				(width 0.1)
				(type default)
			)
			(layer "B.Fab")
		)
		(fp_line
			(start -1.1049 -0.724916)
			(end 1.1049 -0.724916)
			(stroke
				(width 0.1)
				(type default)
			)
			(layer "B.Fab")
		)
		(fp_line
			(start 1.1049 -0.724916)
			(end 1.1049 0.724916)
			(stroke
				(width 0.1)
				(type default)
			)
			(layer "B.Fab")
		)
		(pad "1" smd rect
			(at 0.889 0 270)
			(size 1.016 1.27)
			(layers "B.Cu" "B.Mask" "B.Paste")
			(net "PVCCIN_CPU0")
		)
		(pad "2" smd rect
			(at -0.889 0 270)
			(size 1.016 1.27)
			(layers "B.Cu" "B.Mask" "B.Paste")
			(net "GND")
		)
	)
	(footprint ""
		(layer "B.Cu")
		(at 431.248058 -366.70869 180)
		(property "Reference" "PC1676"
			(at 0 0 0)
			(layer "B.SilkS")
			(hide yes)
			(effects
				(font
					(size 1.27 1.27)
				)
				(justify mirror)
			)
		)
		(property "Value" ""
			(at 0 0 0)
			(layer "B.Fab")
			(effects
				(font
					(size 1.27 1.27)
				)
				(justify mirror)
			)
		)
		(duplicate_pad_numbers_are_jumpers no)
		(fp_line
			(start 1.524 0.762)
			(end 1.524 -0.762)
			(stroke
				(width 0.1524)
				(type default)
			)
			(layer "B.SilkS")
		)
		(fp_line
			(start 1.524 -0.762)
			(end -1.524 -0.762)
			(stroke
				(width 0.1524)
				(type default)
			)
			(layer "B.SilkS")
		)
		(fp_line
			(start -1.524 0.762)
			(end 1.524 0.762)
			(stroke
				(width 0.1524)
				(type default)
			)
			(layer "B.SilkS")
		)
		(fp_line
			(start -1.524 -0.762)
			(end -1.524 0.762)
			(stroke
				(width 0.1524)
				(type default)
			)
			(layer "B.SilkS")
		)
		(fp_line
			(start 1.1049 0.724916)
			(end -1.1049 0.724916)
			(stroke
				(width 0.1)
				(type default)
			)
			(layer "B.Fab")
		)
		(fp_line
			(start 1.1049 -0.724916)
			(end 1.1049 0.724916)
			(stroke
				(width 0.1)
				(type default)
			)
			(layer "B.Fab")
		)
		(fp_line
			(start -1.1049 0.724916)
			(end -1.1049 -0.724916)
			(stroke
				(width 0.1)
				(type default)
			)
			(layer "B.Fab")
		)
		(fp_line
			(start -1.1049 -0.724916)
			(end 1.1049 -0.724916)
			(stroke
				(width 0.1)
				(type default)
			)
			(layer "B.Fab")
		)
		(pad "1" smd rect
			(at 0.889 0 180)
			(size 1.016 1.27)
			(layers "B.Cu" "B.Mask" "B.Paste")
			(net "SW_P12V_PVCCFA_EHV_FIVRA_CPU0_R")
		)
		(pad "2" smd rect
			(at -0.889 0 180)
			(size 1.016 1.27)
			(layers "B.Cu" "B.Mask" "B.Paste")
			(net "GND")
		)
	)
	(footprint ""
		(layer "B.Cu")
		(at 41.535858 -346.579952 -90)
		(property "Reference" "PC2172"
			(at 0 0 90)
			(layer "B.SilkS")
			(hide yes)
			(effects
				(font
					(size 1.27 1.27)
				)
				(justify mirror)
			)
		)
		(property "Value" ""
			(at 0 0 90)
			(layer "B.Fab")
			(effects
				(font
					(size 1.27 1.27)
				)
				(justify mirror)
			)
		)
		(duplicate_pad_numbers_are_jumpers no)
		(fp_line
			(start -4.533392 2.249932)
			(end 4.533392 2.249932)
			(stroke
				(width 0.1524)
				(type default)
			)
			(layer "B.SilkS")
		)
		(fp_line
			(start 4.533392 2.249932)
			(end 4.533392 -2.249932)
			(stroke
				(width 0.1524)
				(type default)
			)
			(layer "B.SilkS")
		)
		(fp_line
			(start -4.533392 -2.249932)
			(end -4.533392 2.249932)
			(stroke
				(width 0.1524)
				(type default)
			)
			(layer "B.SilkS")
		)
		(fp_line
			(start 4.533392 -2.249932)
			(end -4.533392 -2.249932)
			(stroke
				(width 0.1524)
				(type default)
			)
			(layer "B.SilkS")
		)
		(fp_poly
			(pts
				(xy 4.533392 -2.326132) (xy 5.39242 -2.326132) (xy 5.39242 2.326132) (xy 4.533392 2.326132)
			)
			(stroke
				(width 0)
				(type default)
			)
			(fill yes)
			(layer "B.SilkS")
		)
		(fp_line
			(start -3.750056 2.249932)
			(end 3.750056 2.249932)
			(stroke
				(width 0.1)
				(type default)
			)
			(layer "B.Fab")
		)
		(fp_line
			(start 3.750056 2.249932)
			(end 3.750056 -2.249932)
			(stroke
				(width 0.1)
				(type default)
			)
			(layer "B.Fab")
		)
		(fp_line
			(start -3.750056 -2.249932)
			(end -3.750056 2.249932)
			(stroke
				(width 0.1)
				(type default)
			)
			(layer "B.Fab")
		)
		(fp_line
			(start 3.750056 -2.249932)
			(end -3.750056 -2.249932)
			(stroke
				(width 0.1)
				(type default)
			)
			(layer "B.Fab")
		)
		(fp_text user "+"
			(at 6.322314 0.786384 180)
			(unlocked yes)
			(layer "B.SilkS")
			(effects
				(font
					(size 1.905 1.4224)
					(thickness 0.1524)
				)
				(justify left mirror)
			)
		)
		(fp_text user "-"
			(at -4.8514 -0.14605 270)
			(unlocked yes)
			(layer "B.SilkS")
			(effects
				(font
					(size 1.905 1.4224)
					(thickness 0.1524)
				)
				(justify left mirror)
			)
		)
		(fp_text user "+"
			(at 6.322314 0.786384 180)
			(unlocked yes)
			(layer "B.Fab")
			(effects
				(font
					(size 1.905 1.4224)
					(thickness 0.1524)
				)
				(justify left mirror)
			)
		)
		(fp_text user "-"
			(at -4.8514 -0.14605 270)
			(unlocked yes)
			(layer "B.Fab")
			(effects
				(font
					(size 1.905 1.4224)
					(thickness 0.1524)
				)
				(justify left mirror)
			)
		)
		(pad "1" smd rect
			(at 3.199892 0 90)
			(size 2.413 2.8194)
			(layers "B.Cu" "B.Mask" "B.Paste")
			(net "PVCCFA_EHV_FIVRA_CPU1")
		)
		(pad "2" smd rect
			(at -3.199892 0 90)
			(size 2.413 2.8194)
			(layers "B.Cu" "B.Mask" "B.Paste")
			(net "GND")
		)
	)
)
